# S9S_MB_2U (Grand Teton) — schematic netlist excerpt (pin names and nets, part order shuffled) for the footprints in the layout excerpt that follows; sources: Cadence DE-HDL packaged netlist, KiCad conversion of 03242023_DA0F0TMBIJ0_F0T_Motherboard_J_brd_V01_OCP.brd

R1020  Q_RES  0 5% CHIP  pkg 0402LF  page 209 : A = CLK_25M_CK440_CPU0_R_DP ; B = CLK_25M_NSSC_CPU0_DP
R267  Q_RES  240 1% EMPTY  pkg 0402LF  page 119 : A = PVNN_TERM_CPU1 ; B = PU_CPU1_SOCKET_ID2

(kicad_pcb
	(version 20260206)
	(generator "pcbnew")
	(generator_version "10.0")
	(general
		(thickness 1.6)
		(legacy_teardrops no)
	)
	(paper "A4")
	(title_block
		(title "03242023_DA0F0TMBIJ0_F0T_Motherboard_J_brd_V01_OCP.brd")
		(comment 1 "Grand Teton / footprints 5093-5094 of 6105")
	)
	(layers
		(0 "F.Cu" signal "TOP")
		(4 "In1.Cu" signal "GND")
		(6 "In2.Cu" signal "IN1")
		(8 "In3.Cu" signal "GND1")
		(10 "In4.Cu" signal "IN2")
		(12 "In5.Cu" signal "GND2")
		(14 "In6.Cu" signal "IN3")
		(16 "In7.Cu" signal "GND3")
		(18 "In8.Cu" signal "VCC")
		(20 "In9.Cu" signal "VCC1")
		(22 "In10.Cu" signal "GND4")
		(24 "In11.Cu" signal "IN4")
		(26 "In12.Cu" signal "GND5")
		(28 "In13.Cu" signal "IN5")
		(30 "In14.Cu" signal "GND6")
		(32 "In15.Cu" signal "IN6")
		(34 "In16.Cu" signal "GND7")
		(2 "B.Cu" signal "BOTTOM")
		(9 "F.Adhes" user "F.Adhesive")
		(11 "B.Adhes" user "B.Adhesive")
		(13 "F.Paste" user "Package Geometry/Pastemask Top")
		(15 "B.Paste" user "Package Geometry/Pastemask Bottom")
		(5 "F.SilkS" user "Ref Des/Silkscreen Top")
		(7 "B.SilkS" user "Ref Des/Silkscreen Bottom")
		(1 "F.Mask" user "Board Geometry/Soldermask Top")
		(3 "B.Mask" user "Board Geometry/Soldermask Bottom")
		(17 "Dwgs.User" user "User.Drawings")
		(19 "Cmts.User" user "User.Comments")
		(21 "Eco1.User" user "User.Eco1")
		(23 "Eco2.User" user "User.Eco2")
		(25 "Edge.Cuts" user "Board Geometry/Outline")
		(27 "Margin" user)
		(31 "F.CrtYd" user "Package Geometry/Place Bound Top")
		(29 "B.CrtYd" user "Package Geometry/Place Bound Bottom")
		(35 "F.Fab" user "Ref Des/Assembly Top")
		(33 "B.Fab" user "Ref Des/Assembly Bottom")
	)
	(footprint ""
		(layer "B.Cu")
		(at 178.145948 -192.699894 -90)
		(property "Reference" "R267"
			(at 0 0 90)
			(layer "B.SilkS")
			(hide yes)
			(effects
				(font
					(size 1.27 1.27)
				)
				(justify mirror)
			)
		)
		(property "Value" ""
			(at 0 0 90)
			(layer "B.Fab")
			(effects
				(font
					(size 1.27 1.27)
				)
				(justify mirror)
			)
		)
		(duplicate_pad_numbers_are_jumpers no)
		(fp_line
			(start -0.7874 0.4064)
			(end 0.7874 0.4064)
			(stroke
				(width 0.1524)
				(type default)
			)
			(layer "B.SilkS")
		)
		(fp_line
			(start 0.7874 0.4064)
			(end 0.7874 -0.4064)
			(stroke
				(width 0.1524)
				(type default)
			)
			(layer "B.SilkS")
		)
		(fp_line
			(start -0.7874 -0.4064)
			(end -0.7874 0.4064)
			(stroke
				(width 0.1524)
				(type default)
			)
			(layer "B.SilkS")
		)
		(fp_line
			(start 0.7874 -0.4064)
			(end -0.7874 -0.4064)
			(stroke
				(width 0.1524)
				(type default)
			)
			(layer "B.SilkS")
		)
		(fp_line
			(start -0.67945 0.3048)
			(end -0.120396 0.3048)
			(stroke
				(width 0.1)
				(type default)
			)
			(layer "B.Fab")
		)
		(fp_line
			(start -0.120396 0.3048)
			(end -0.120396 0.2794)
			(stroke
				(width 0.1)
				(type default)
			)
			(layer "B.Fab")
		)
		(fp_line
			(start 0.12065 0.3048)
			(end 0.67945 0.3048)
			(stroke
				(width 0.1)
				(type default)
			)
			(layer "B.Fab")
		)
		(fp_line
			(start 0.67945 0.3048)
			(end 0.67945 -0.305054)
			(stroke
				(width 0.1)
				(type default)
			)
			(layer "B.Fab")
		)
		(fp_line
			(start -0.120396 0.2794)
			(end 0.12065 0.2794)
			(stroke
				(width 0.1)
				(type default)
			)
			(layer "B.Fab")
		)
		(fp_line
			(start 0.12065 0.2794)
			(end 0.12065 0.3048)
			(stroke
				(width 0.1)
				(type default)
			)
			(layer "B.Fab")
		)
		(fp_line
			(start -0.12065 -0.2794)
			(end -0.12065 -0.3048)
			(stroke
				(width 0.1)
				(type default)
			)
			(layer "B.Fab")
		)
		(fp_line
			(start 0.12065 -0.2794)
			(end -0.12065 -0.2794)
			(stroke
				(width 0.1)
				(type default)
			)
			(layer "B.Fab")
		)
		(fp_line
			(start -0.67945 -0.3048)
			(end -0.67945 0.3048)
			(stroke
				(width 0.1)
				(type default)
			)
			(layer "B.Fab")
		)
		(fp_line
			(start -0.12065 -0.3048)
			(end -0.67945 -0.3048)
			(stroke
				(width 0.1)
				(type default)
			)
			(layer "B.Fab")
		)
		(fp_line
			(start 0.12065 -0.305054)
			(end 0.12065 -0.2794)
			(stroke
				(width 0.1)
				(type default)
			)
			(layer "B.Fab")
		)
		(fp_line
			(start 0.67945 -0.305054)
			(end 0.12065 -0.305054)
			(stroke
				(width 0.1)
				(type default)
			)
			(layer "B.Fab")
		)
		(pad "1" smd circle
			(at 0.40005 0 90)
			(size 0 0)
			(layers "B.Cu" "B.Mask" "B.Paste")
			(net "PVNN_TERM_CPU1")
		)
		(pad "2" smd circle
			(at -0.40005 0 90)
			(size 0 0)
			(layers "B.Cu" "B.Mask" "B.Paste")
			(net "PU_CPU1_SOCKET_ID2")
		)
	)
	(footprint ""
		(layer "B.Cu")
		(at 337.641692 -137.832338 180)
		(property "Reference" "R1020"
			(at 0 0 0)
			(layer "B.SilkS")
			(hide yes)
			(effects
				(font
					(size 1.27 1.27)
				)
				(justify mirror)
			)
		)
		(property "Value" ""
			(at 0 0 0)
			(layer "B.Fab")
			(effects
				(font
					(size 1.27 1.27)
				)
				(justify mirror)
			)
		)
		(duplicate_pad_numbers_are_jumpers no)
		(fp_line
			(start 0.7874 0.4064)
			(end 0.7874 0.05207)
			(stroke
				(width 0.1524)
				(type default)
			)
			(layer "B.SilkS")
		)
		(fp_line
			(start 0.515112 -0.4064)
			(end -0.518668 -0.4064)
			(stroke
				(width 0.1524)
				(type default)
			)
			(layer "B.SilkS")
		)
		(fp_line
			(start -0.7874 0.4064)
			(end 0.7874 0.4064)
			(stroke
				(width 0.1524)
				(type default)
			)
			(layer "B.SilkS")
		)
		(fp_line
			(start -0.7874 -0.09017)
			(end -0.7874 0.4064)
			(stroke
				(width 0.1524)
				(type default)
			)
			(layer "B.SilkS")
		)
		(fp_line
			(start 0.67945 0.3048)
			(end 0.67945 -0.305054)
			(stroke
				(width 0.1)
				(type default)
			)
			(layer "B.Fab")
		)
		(fp_line
			(start 0.67945 -0.305054)
			(end 0.12065 -0.305054)
			(stroke
				(width 0.1)
				(type default)
			)
			(layer "B.Fab")
		)
		(fp_line
			(start 0.12065 0.3048)
			(end 0.67945 0.3048)
			(stroke
				(width 0.1)
				(type default)
			)
			(layer "B.Fab")
		)
		(fp_line
			(start 0.12065 0.2794)
			(end 0.12065 0.3048)
			(stroke
				(width 0.1)
				(type default)
			)
			(layer "B.Fab")
		)
		(fp_line
			(start 0.12065 -0.2794)
			(end -0.12065 -0.2794)
			(stroke
				(width 0.1)
				(type default)
			)
			(layer "B.Fab")
		)
		(fp_line
			(start 0.12065 -0.305054)
			(end 0.12065 -0.2794)
			(stroke
				(width 0.1)
				(type default)
			)
			(layer "B.Fab")
		)
		(fp_line
			(start -0.120396 0.3048)
			(end -0.120396 0.2794)
			(stroke
				(width 0.1)
				(type default)
			)
			(layer "B.Fab")
		)
		(fp_line
			(start -0.120396 0.2794)
			(end 0.12065 0.2794)
			(stroke
				(width 0.1)
				(type default)
			)
			(layer "B.Fab")
		)
		(fp_line
			(start -0.12065 -0.2794)
			(end -0.12065 -0.3048)
			(stroke
				(width 0.1)
				(type default)
			)
			(layer "B.Fab")
		)
		(fp_line
			(start -0.12065 -0.3048)
			(end -0.67945 -0.3048)
			(stroke
				(width 0.1)
				(type default)
			)
			(layer "B.Fab")
		)
		(fp_line
			(start -0.67945 0.3048)
			(end -0.120396 0.3048)
			(stroke
				(width 0.1)
				(type default)
			)
			(layer "B.Fab")
		)
		(fp_line
			(start -0.67945 -0.3048)
			(end -0.67945 0.3048)
			(stroke
				(width 0.1)
				(type default)
			)
			(layer "B.Fab")
		)
		(pad "1" smd rect
			(at 0.40005 0 180)
			(size 0.4572 0.508)
			(layers "B.Cu" "B.Mask" "B.Paste")
			(net "CLK_25M_CK440_CPU0_R_DP")
		)
		(pad "2" smd rect
			(at -0.40005 0 180)
			(size 0.4572 0.508)
			(layers "B.Cu" "B.Mask" "B.Paste")
			(net "CLK_25M_NSSC_CPU0_DP")
		)
	)
)
